(kicad_pcb
	(version 20241229)
	(generator "pcbnew")
	(generator_version "9.0")
	(general
		(thickness 1.294)
		(legacy_teardrops no)
	)
	(paper "A3")
	(title_block
		(title "Kintex 410T devboard")
		(date "2024-04-03")
		(rev "1.1.2")
		(comment 9 "footprints 243-247 of 975")
	)
	(layers
		(0 "F.Cu" mixed)
		(4 "In1.Cu" power)
		(6 "In2.Cu" power)
		(8 "In3.Cu" mixed)
		(10 "In4.Cu" power)
		(12 "In5.Cu" mixed)
		(14 "In6.Cu" power)
		(16 "In7.Cu" mixed)
		(18 "In8.Cu" power)
		(2 "B.Cu" mixed)
		(9 "F.Adhes" user "F.Adhesive")
		(11 "B.Adhes" user "B.Adhesive")
		(13 "F.Paste" user)
		(15 "B.Paste" user)
		(5 "F.SilkS" user "F.Silkscreen")
		(7 "B.SilkS" user "B.Silkscreen")
		(1 "F.Mask" user)
		(3 "B.Mask" user)
		(17 "Dwgs.User" user "User.Drawings")
		(19 "Cmts.User" user "User.Comments")
		(21 "Eco1.User" user "User.Eco1")
		(23 "Eco2.User" user "User.Eco2")
		(25 "Edge.Cuts" user)
		(27 "Margin" user)
		(31 "F.CrtYd" user "F.Courtyard")
		(29 "B.CrtYd" user "B.Courtyard")
		(35 "F.Fab" user)
		(33 "B.Fab" user)
	)
	(footprint "antmicro-footprints:FB_0603_1608Metric"
		(layer "F.Cu")
		(at 228.39 145.58)
		(property "Reference" "FB12"
			(at 1.26 0.27 0)
			(layer "F.SilkS")
			(effects
				(font
					(size 0.7 0.7)
					(thickness 0.15)
				)
				(justify left bottom)
			)
		)
		(property "Value" "FB_120Z_2A_Murata-BLM18PG_0603"
			(at 0 1.7 0)
			(layer "F.Fab")
			(effects
				(font
					(size 0.7 0.7)
					(thickness 0.15)
				)
				(justify left bottom)
			)
		)
		(property "Description" "Ferrite Bead, 0603 [1608 Metric], 120 ohm, 2 A, BLM18P, 0.05 ohm, ± 25%, DC power line"
			(at 0 0 0)
			(layer "F.Fab")
			(hide yes)
			(effects
				(font
					(size 1.27 1.27)
					(thickness 0.15)
				)
			)
		)
		(property "Author" "Antmicro"
			(at 0 0 0)
			(layer "F.Fab")
			(hide yes)
			(effects
				(font
					(size 1 1)
					(thickness 0.15)
				)
			)
		)
		(property "Current" ""
			(at 0 0 0)
			(layer "F.Fab")
			(hide yes)
			(effects
				(font
					(size 1 1)
					(thickness 0.15)
				)
			)
		)
		(property "License" "Apache-2.0"
			(at 0 0 0)
			(layer "F.Fab")
			(hide yes)
			(effects
				(font
					(size 1 1)
					(thickness 0.15)
				)
			)
		)
		(property "MPN" "BLM18PG121SN1D"
			(at 0 0 0)
			(layer "F.Fab")
			(hide yes)
			(effects
				(font
					(size 1 1)
					(thickness 0.15)
				)
			)
		)
		(property "Manufacturer" "Murata"
			(at 0 0 0)
			(layer "F.Fab")
			(hide yes)
			(effects
				(font
					(size 1 1)
					(thickness 0.15)
				)
			)
		)
		(property "Val" "120Z/2A"
			(at 0 0 0)
			(layer "F.Fab")
			(hide yes)
			(effects
				(font
					(size 1 1)
					(thickness 0.15)
				)
			)
		)
		(sheetname "Clocks")
		(sheetfile "clocks.kicad_sch")
		(attr smd)
		(fp_line
			(start -0.15 -0.4)
			(end 0.15 -0.4)
			(stroke
				(width 0.15)
				(type solid)
			)
			(layer "F.SilkS")
		)
		(fp_line
			(start -0.15 0.4)
			(end 0.15 0.4)
			(stroke
				(width 0.15)
				(type solid)
			)
			(layer "F.SilkS")
		)
		(fp_rect
			(start -1.25 -0.65)
			(end 1.25 0.65)
			(stroke
				(width 0.05)
				(type solid)
			)
			(fill no)
			(layer "F.CrtYd")
		)
		(fp_line
			(start -0.803 0.406)
			(end -0.803 -0.408)
			(stroke
				(width 0.15)
				(type solid)
			)
			(layer "F.Fab")
		)
		(fp_line
			(start 0.8 -0.408)
			(end -0.803 -0.408)
			(stroke
				(width 0.15)
				(type solid)
			)
			(layer "F.Fab")
		)
		(fp_line
			(start 0.8 -0.408)
			(end 0.8 0.406)
			(stroke
				(width 0.15)
				(type solid)
			)
			(layer "F.Fab")
		)
		(fp_line
			(start 0.8 0.406)
			(end -0.803 0.406)
			(stroke
				(width 0.15)
				(type solid)
			)
			(layer "F.Fab")
		)
		(pad "1" smd roundrect
			(at -0.7 0)
			(size 0.8 1)
			(layers "F.Cu" "F.Mask" "F.Paste")
			(roundrect_rratio 0.2)
			(net 1231 "Net-(C366-Pad2)")
			(pintype "passive")
		)
		(pad "2" smd roundrect
			(at 0.7 0)
			(size 0.8 1)
			(layers "F.Cu" "F.Mask" "F.Paste")
			(roundrect_rratio 0.2)
			(net 24 "+3V3")
			(pintype "passive")
		)
	)
	(footprint "antmicro-footprints:PinHeader_2x3_P2.54mm_SMD"
		(layer "F.Cu")
		(at 212.7 88.4)
		(property "Reference" "J20"
			(at 3.55 3.45 180)
			(layer "F.SilkS")
			(effects
				(font
					(size 0.7 0.7)
					(thickness 0.15)
				)
				(justify left bottom)
			)
		)
		(property "Value" "PinHeader_2x3_P2.54mm_SMD"
			(at 5.31 10.794 90)
			(layer "F.Fab")
			(effects
				(font
					(size 0.7 0.7)
					(thickness 0.15)
				)
				(justify left bottom)
			)
		)
		(property "Author" "Antmicro"
			(at 0 0 0)
			(layer "F.Fab")
			(hide yes)
			(effects
				(font
					(size 1 1)
					(thickness 0.15)
				)
			)
		)
		(property "License" "Apache-2.0"
			(at 0 0 0)
			(layer "F.Fab")
			(hide yes)
			(effects
				(font
					(size 1 1)
					(thickness 0.15)
				)
			)
		)
		(property "MPN" "15910060"
			(at 0 0 0)
			(layer "F.Fab")
			(hide yes)
			(effects
				(font
					(size 1 1)
					(thickness 0.15)
				)
			)
		)
		(property "Manufacturer" "Molex"
			(at 0 0 0)
			(layer "F.Fab")
			(hide yes)
			(effects
				(font
					(size 1 1)
					(thickness 0.15)
				)
			)
		)
		(sheetname "FPGA supply")
		(sheetfile "fpga-supply.kicad_sch")
		(attr smd)
		(fp_line
			(start -3.809 -2.555)
			(end -3.269 -2.555)
			(stroke
				(width 0.15)
				(type solid)
			)
			(layer "F.SilkS")
		)
		(fp_line
			(start -3.809 2.521)
			(end -3.809 -2.555)
			(stroke
				(width 0.15)
				(type solid)
			)
			(layer "F.SilkS")
		)
		(fp_line
			(start -3.809 2.521)
			(end -3.269 2.521)
			(stroke
				(width 0.15)
				(type solid)
			)
			(layer "F.SilkS")
		)
		(fp_line
			(start 3.81 -2.555)
			(end 3.27 -2.555)
			(stroke
				(width 0.15)
				(type solid)
			)
			(layer "F.SilkS")
		)
		(fp_line
			(start 3.81 -2.555)
			(end 3.81 2.521)
			(stroke
				(width 0.15)
				(type solid)
			)
			(layer "F.SilkS")
		)
		(fp_line
			(start 3.81 2.521)
			(end 3.27 2.521)
			(stroke
				(width 0.15)
				(type solid)
			)
			(layer "F.SilkS")
		)
		(fp_circle
			(center -3.45 2.95)
			(end -3.397 2.95)
			(stroke
				(width 0.15)
				(type solid)
			)
			(fill yes)
			(layer "F.SilkS")
		)
		(fp_rect
			(start -4.31 -4.103)
			(end 4.309 4.101)
			(stroke
				(width 0.05)
				(type solid)
			)
			(fill no)
			(layer "F.CrtYd")
		)
		(fp_line
			(start -3.81 3.29)
			(end -3.61 3.49)
			(stroke
				(width 0.15)
				(type solid)
			)
			(layer "F.Fab")
		)
		(fp_rect
			(start -3.81 -3.493)
			(end 3.809 3.491)
			(stroke
				(width 0.15)
				(type solid)
			)
			(fill no)
			(layer "F.Fab")
		)
		(pad "1" smd rect
			(at -2.539 2.2)
			(size 1.27 3.68)
			(layers "F.Cu" "F.Mask" "F.Paste")
			(net 3 "VCC_USR_B")
			(pintype "passive")
		)
		(pad "2" smd rect
			(at -2.539 -2.2 180)
			(size 1.27 3.68)
			(layers "F.Cu" "F.Mask" "F.Paste")
			(net 24 "+3V3")
			(pintype "passive")
		)
		(pad "3" smd rect
			(at 0 2.2)
			(size 1.27 3.68)
			(layers "F.Cu" "F.Mask" "F.Paste")
			(net 26 "+1V8")
			(pintype "passive")
		)
		(pad "4" smd rect
			(at 0 -2.2 180)
			(size 1.27 3.68)
			(layers "F.Cu" "F.Mask" "F.Paste")
			(net 3 "VCC_USR_B")
			(pintype "passive")
		)
		(pad "5" smd rect
			(at 2.539 2.2)
			(size 1.27 3.68)
			(layers "F.Cu" "F.Mask" "F.Paste")
			(net 3 "VCC_USR_B")
			(pintype "passive")
		)
		(pad "6" smd rect
			(at 2.539 -2.2 180)
			(size 1.27 3.68)
			(layers "F.Cu" "F.Mask" "F.Paste")
			(net 727 "+1V2")
			(pintype "passive")
		)
	)
	(footprint "antmicro-footprints:R_0402_1005Metric"
		(layer "F.Cu")
		(at 173.570001 106.476251)
		(descr "Resistor SMD 0402")
		(tags "resistor SMD 0402")
		(property "Reference" "R272"
			(at 0.929999 0.376249 0)
			(layer "F.SilkS")
			(effects
				(font
					(size 0.7 0.7)
					(thickness 0.15)
				)
				(justify left bottom)
			)
		)
		(property "Value" "R_33R_0402"
			(at 0 1.4 0)
			(layer "F.Fab")
			(effects
				(font
					(size 0.7 0.7)
					(thickness 0.15)
				)
				(justify left bottom)
			)
		)
		(property "Description" "SMD Chip Resistor, 33 ohm, ± 1%, 62.5 mW, 0402 [1005 Metric], Thick Film, General Purpose"
			(at 0 0 0)
			(layer "F.Fab")
			(hide yes)
			(effects
				(font
					(size 1.27 1.27)
					(thickness 0.15)
				)
			)
		)
		(property "Author" "Antmicro"
			(at 0 0 0)
			(layer "F.Fab")
			(hide yes)
			(effects
				(font
					(size 1 1)
					(thickness 0.15)
				)
			)
		)
		(property "License" "Apache-2.0"
			(at 0 0 0)
			(layer "F.Fab")
			(hide yes)
			(effects
				(font
					(size 1 1)
					(thickness 0.15)
				)
			)
		)
		(property "MPN" "CR0402-FX-33R0GLF"
			(at 0 0 0)
			(layer "F.Fab")
			(hide yes)
			(effects
				(font
					(size 1 1)
					(thickness 0.15)
				)
			)
		)
		(property "Manufacturer" "Bourns"
			(at 0 0 0)
			(layer "F.Fab")
			(hide yes)
			(effects
				(font
					(size 1 1)
					(thickness 0.15)
				)
			)
		)
		(property "Tolerance" "1%"
			(at 0 0 0)
			(layer "F.Fab")
			(hide yes)
			(effects
				(font
					(size 1 1)
					(thickness 0.15)
				)
			)
		)
		(property "Val" "33R"
			(at 0 0 0)
			(layer "F.Fab")
			(hide yes)
			(effects
				(font
					(size 1 1)
					(thickness 0.15)
				)
			)
		)
		(sheetname "FMC+ HSPC")
		(sheetfile "fmc-hspc.kicad_sch")
		(attr smd)
		(fp_rect
			(start -0.925 -0.47)
			(end 0.925 0.47)
			(stroke
				(width 0.05)
				(type default)
			)
			(fill no)
			(layer "F.CrtYd")
		)
		(fp_rect
			(start -0.5 -0.25)
			(end 0.5 0.25)
			(stroke
				(width 0.15)
				(type solid)
			)
			(fill no)
			(layer "F.Fab")
		)
		(pad "1" smd roundrect
			(at -0.48 0)
			(size 0.59 0.64)
			(layers "F.Cu" "F.Mask" "F.Paste")
			(roundrect_rratio 0.25)
			(net 478 "/FMC+ HSPC/GTR_REFCLK1_R_N")
			(pintype "passive")
		)
		(pad "2" smd roundrect
			(at 0.48 0)
			(size 0.59 0.64)
			(layers "F.Cu" "F.Mask" "F.Paste")
			(roundrect_rratio 0.25)
			(net 592 "/FMC+ HSPC/GTX115.REFCLK1_N")
			(pintype "passive")
		)
	)
	(footprint "antmicro-footprints:R_Array_4x0201_Panasonic_EXB18V"
		(layer "F.Cu")
		(at 249.4 122)
		(property "Reference" "R26"
			(at 1.15 -0.8 0)
			(layer "F.SilkS")
			(effects
				(font
					(size 0.7 0.7)
					(thickness 0.15)
				)
				(justify right bottom)
			)
		)
		(property "Value" "R_4x33R_0201_array"
			(at -1.1 1.8 0)
			(layer "F.Fab")
			(effects
				(font
					(size 0.7 0.7)
					(thickness 0.15)
				)
				(justify left bottom)
			)
		)
		(property "Description" "Fixed Network Resistor, 33 ohm, Isolated, 4 Resistors, 0502 [1406 Metric], Flat, ± 5%"
			(at 0 0 0)
			(layer "F.Fab")
			(hide yes)
			(effects
				(font
					(size 1.27 1.27)
					(thickness 0.15)
				)
			)
		)
		(property "Author" "Antmicro"
			(at 0 0 0)
			(layer "F.Fab")
			(hide yes)
			(effects
				(font
					(size 1 1)
					(thickness 0.15)
				)
			)
		)
		(property "License" "Apache-2.0"
			(at 0 0 0)
			(layer "F.Fab")
			(hide yes)
			(effects
				(font
					(size 1 1)
					(thickness 0.15)
				)
			)
		)
		(property "MPN" "EXB-18V330JX"
			(at 0 0 0)
			(layer "F.Fab")
			(hide yes)
			(effects
				(font
					(size 1 1)
					(thickness 0.15)
				)
			)
		)
		(property "Manufacturer" "Panasonic"
			(at 0 0 0)
			(layer "F.Fab")
			(hide yes)
			(effects
				(font
					(size 1 1)
					(thickness 0.15)
				)
			)
		)
		(property "Val" "R_4x33R_0201"
			(at 0 0 0)
			(layer "F.Fab")
			(hide yes)
			(effects
				(font
					(size 1 1)
					(thickness 0.15)
				)
			)
		)
		(sheetname "Supervisior MCU")
		(sheetfile "supervisor-mcu.kicad_sch")
		(attr smd)
		(fp_line
			(start -0.8 -0.45)
			(end -0.8 0.45)
			(stroke
				(width 0.12)
				(type solid)
			)
			(layer "F.SilkS")
		)
		(fp_line
			(start 0.8 -0.45)
			(end 0.8 0.45)
			(stroke
				(width 0.12)
				(type solid)
			)
			(layer "F.SilkS")
		)
		(fp_rect
			(start -0.898 -0.66)
			(end 0.898 0.65)
			(stroke
				(width 0.05)
				(type solid)
			)
			(fill no)
			(layer "F.CrtYd")
		)
		(pad "1" smd roundrect
			(at -0.6 0.298)
			(size 0.2 0.4)
			(layers "F.Cu" "F.Mask" "F.Paste")
			(roundrect_rratio 0.25)
			(net 111 "/Supervisior MCU/FAN_PWM")
			(pinfunction "R1.1")
			(pintype "passive")
		)
		(pad "2" smd roundrect
			(at -0.202 0.298)
			(size 0.2 0.4)
			(layers "F.Cu" "F.Mask" "F.Paste")
			(roundrect_rratio 0.25)
			(net 1073 "/Supervisior MCU/USB_A12")
			(pinfunction "R2.1")
			(pintype "passive")
		)
		(pad "3" smd roundrect
			(at 0.2 0.298)
			(size 0.2 0.4)
			(layers "F.Cu" "F.Mask" "F.Paste")
			(roundrect_rratio 0.25)
			(net 1072 "/Supervisior MCU/USB_A11")
			(pinfunction "R3.1")
			(pintype "passive")
		)
		(pad "4" smd roundrect
			(at 0.598 0.298)
			(size 0.2 0.4)
			(layers "F.Cu" "F.Mask" "F.Paste")
			(roundrect_rratio 0.25)
			(net 1071 "/Supervisior MCU/USB_A10")
			(pinfunction "R4.1")
			(pintype "passive")
		)
		(pad "5" smd roundrect
			(at 0.598 -0.3)
			(size 0.2 0.4)
			(layers "F.Cu" "F.Mask" "F.Paste")
			(roundrect_rratio 0.25)
			(net 1369 "/SUP_MCU.A10")
			(pinfunction "R4.2")
			(pintype "passive")
		)
		(pad "6" smd roundrect
			(at 0.2 -0.3)
			(size 0.2 0.4)
			(layers "F.Cu" "F.Mask" "F.Paste")
			(roundrect_rratio 0.25)
			(net 1370 "/SUP_MCU.A11")
			(pinfunction "R3.2")
			(pintype "passive")
		)
		(pad "7" smd roundrect
			(at -0.202 -0.3)
			(size 0.2 0.4)
			(layers "F.Cu" "F.Mask" "F.Paste")
			(roundrect_rratio 0.25)
			(net 1371 "/SUP_MCU.A12")
			(pinfunction "R2.2")
			(pintype "passive")
		)
		(pad "8" smd roundrect
			(at -0.6 -0.3)
			(size 0.2 0.4)
			(layers "F.Cu" "F.Mask" "F.Paste")
			(roundrect_rratio 0.25)
			(net 1350 "/SUP_MCU.FAN_PWM")
			(pinfunction "R1.2")
			(pintype "passive")
		)
	)
	(footprint "antmicro-footprints:R_0402_1005Metric"
		(layer "F.Cu")
		(at 218.4 151.8)
		(descr "Resistor SMD 0402")
		(tags "resistor SMD 0402")
		(property "Reference" "R232"
			(at -3.6 0.35 0)
			(layer "F.SilkS")
			(effects
				(font
					(size 0.7 0.7)
					(thickness 0.15)
				)
				(justify left bottom)
			)
		)
		(property "Value" "R_10R_0402"
			(at 0 1.4 0)
			(layer "F.Fab")
			(effects
				(font
					(size 0.7 0.7)
					(thickness 0.15)
				)
				(justify left bottom)
			)
		)
		(property "Description" "SMD Chip Resistor, 10 ohm, ± 1%, 62.5 mW, 0402 [1005 Metric], Thick Film, General Purpose"
			(at 0 0 0)
			(layer "F.Fab")
			(hide yes)
			(effects
				(font
					(size 1.27 1.27)
					(thickness 0.15)
				)
			)
		)
		(property "Author" "Antmicro"
			(at 0 0 0)
			(layer "F.Fab")
			(hide yes)
			(effects
				(font
					(size 1 1)
					(thickness 0.15)
				)
			)
		)
		(property "License" "Apache-2.0"
			(at 0 0 0)
			(layer "F.Fab")
			(hide yes)
			(effects
				(font
					(size 1 1)
					(thickness 0.15)
				)
			)
		)
		(property "MPN" "CR0402-FX-10R0GLF"
			(at 0 0 0)
			(layer "F.Fab")
			(hide yes)
			(effects
				(font
					(size 1 1)
					(thickness 0.15)
				)
			)
		)
		(property "Manufacturer" "Bourns"
			(at 0 0 0)
			(layer "F.Fab")
			(hide yes)
			(effects
				(font
					(size 1 1)
					(thickness 0.15)
				)
			)
		)
		(property "Tolerance" "1%"
			(at 0 0 0)
			(layer "F.Fab")
			(hide yes)
			(effects
				(font
					(size 1 1)
					(thickness 0.15)
				)
			)
		)
		(property "Val" "10R"
			(at 0 0 0)
			(layer "F.Fab")
			(hide yes)
			(effects
				(font
					(size 1 1)
					(thickness 0.15)
				)
			)
		)
		(sheetname "HDMI + Ethernet")
		(sheetfile "hdmi-ethernet.kicad_sch")
		(attr smd)
		(fp_rect
			(start -0.925 -0.47)
			(end 0.925 0.47)
			(stroke
				(width 0.05)
				(type default)
			)
			(fill no)
			(layer "F.CrtYd")
		)
		(fp_rect
			(start -0.5 -0.25)
			(end 0.5 0.25)
			(stroke
				(width 0.15)
				(type solid)
			)
			(fill no)
			(layer "F.Fab")
		)
		(pad "1" smd roundrect
			(at -0.48 0)
			(size 0.59 0.64)
			(layers "F.Cu" "F.Mask" "F.Paste")
			(roundrect_rratio 0.25)
			(net 513 "/FPGA Bank 18 & 32/ETH_RMII.TXD0")
			(pintype "passive")
		)
		(pad "2" smd roundrect
			(at 0.48 0)
			(size 0.59 0.64)
			(layers "F.Cu" "F.Mask" "F.Paste")
			(roundrect_rratio 0.25)
			(net 949 "/HDMI + Ethernet/ETH_PHY_TXDO")
			(pintype "passive")
		)
	)
)
